# SCM (Grand Teton) — schematic netlist excerpt (pin names and nets, part order shuffled) for the footprints in the layout excerpt that follows; sources: Cadence DE-HDL packaged netlist, KiCad conversion of 12092022_DA0F0TMDCD0_F0T_Management_Board_D_brd_V3_OCP.brd

PC229  Q_CAP  22UF 10V 20% X6S  pkg C0805  page 52 : A = P3V3_AUX ; B = GND

L21  Q_INDUCTOR4P_12  67/320MA EMPTY  pkg L_DLW21HNXA  page 29
  \1\  = USB3_01_MUX_FB_TXP
  \2\  = USB3_01_FB_TXP
  \3\  = USB3_01_FB_TXN
  \4\  = USB3_01_MUX_FB_TXN

R97  Q_RES  0 5% CHIP  pkg 0402LF  page 46 : A = SPI_BMC_TPM_MOSI_R ; B = SPI_BMC_TPM_MOSI

(kicad_pcb
	(version 20260206)
	(generator "pcbnew")
	(generator_version "10.0")
	(general
		(thickness 1.6)
		(legacy_teardrops no)
	)
	(paper "A4")
	(title_block
		(title "12092022_DA0F0TMDCD0_F0T_Management_Board_D_brd_V3_OCP.brd")
		(comment 1 "Grand Teton / footprints 239-241 of 1440")
	)
	(layers
		(0 "F.Cu" signal "TOP")
		(4 "In1.Cu" signal "GND")
		(6 "In2.Cu" signal "IN1")
		(8 "In3.Cu" signal "GND1")
		(10 "In4.Cu" signal "IN2")
		(12 "In5.Cu" signal "VCC")
		(14 "In6.Cu" signal "VCC1")
		(16 "In7.Cu" signal "IN3")
		(18 "In8.Cu" signal "GND2")
		(20 "In9.Cu" signal "IN4")
		(22 "In10.Cu" signal "GND3")
		(2 "B.Cu" signal "BOTTOM")
		(9 "F.Adhes" user "F.Adhesive")
		(11 "B.Adhes" user "B.Adhesive")
		(13 "F.Paste" user "Package Geometry/Pastemask Top")
		(15 "B.Paste" user "Package Geometry/Pastemask Bottom")
		(5 "F.SilkS" user "Ref Des/Silkscreen Top")
		(7 "B.SilkS" user "Ref Des/Silkscreen Bottom")
		(1 "F.Mask" user "Board Geometry/Soldermask Top")
		(3 "B.Mask" user "Board Geometry/Soldermask Bottom")
		(17 "Dwgs.User" user "User.Drawings")
		(19 "Cmts.User" user "User.Comments")
		(21 "Eco1.User" user "User.Eco1")
		(23 "Eco2.User" user "User.Eco2")
		(25 "Edge.Cuts" user "Board Geometry/Outline")
		(27 "Margin" user)
		(31 "F.CrtYd" user "Package Geometry/Place Bound Top")
		(29 "B.CrtYd" user "Package Geometry/Place Bound Bottom")
		(35 "F.Fab" user "Ref Des/Assembly Top")
		(33 "B.Fab" user "Ref Des/Assembly Bottom")
	)
	(footprint ""
		(layer "F.Cu")
		(at 41.061894 -22.159976)
		(property "Reference" "L21"
			(at 0 0 0)
			(layer "F.SilkS")
			(hide yes)
			(effects
				(font
					(size 1.27 1.27)
				)
			)
		)
		(property "Value" ""
			(at 0 0 0)
			(layer "F.Fab")
			(effects
				(font
					(size 1.27 1.27)
				)
			)
		)
		(duplicate_pad_numbers_are_jumpers no)
		(fp_line
			(start -0.8636 -1.524)
			(end -0.381508 -1.524)
			(stroke
				(width 0.1524)
				(type default)
			)
			(layer "F.SilkS")
		)
		(fp_line
			(start -0.8636 1.524)
			(end -0.8636 -1.524)
			(stroke
				(width 0.1524)
				(type default)
			)
			(layer "F.SilkS")
		)
		(fp_line
			(start -0.465328 1.524)
			(end -0.8636 1.524)
			(stroke
				(width 0.1524)
				(type default)
			)
			(layer "F.SilkS")
		)
		(fp_line
			(start 0.441452 -1.524)
			(end 0.8636 -1.524)
			(stroke
				(width 0.1524)
				(type default)
			)
			(layer "F.SilkS")
		)
		(fp_line
			(start 0.8636 -1.524)
			(end 0.8636 1.524)
			(stroke
				(width 0.1524)
				(type default)
			)
			(layer "F.SilkS")
		)
		(fp_line
			(start 0.8636 1.524)
			(end 0.492252 1.524)
			(stroke
				(width 0.1524)
				(type default)
			)
			(layer "F.SilkS")
		)
		(fp_poly
			(pts
				(xy -0.875538 -1.918208) (xy -1.414272 -2.09804) (xy -1.055116 -2.457196)
			)
			(stroke
				(width 0)
				(type default)
			)
			(fill yes)
			(layer "F.SilkS")
		)
		(fp_line
			(start -0.700024 -1.100074)
			(end 0.700024 -1.100074)
			(stroke
				(width 0.1)
				(type default)
			)
			(layer "F.Fab")
		)
		(fp_line
			(start -0.700024 1.100074)
			(end -0.700024 -1.100074)
			(stroke
				(width 0.1)
				(type default)
			)
			(layer "F.Fab")
		)
		(fp_line
			(start 0.700024 -1.100074)
			(end 0.700024 1.100074)
			(stroke
				(width 0.1)
				(type default)
			)
			(layer "F.Fab")
		)
		(fp_line
			(start 0.700024 1.100074)
			(end -0.700024 1.100074)
			(stroke
				(width 0.1)
				(type default)
			)
			(layer "F.Fab")
		)
		(fp_poly
			(pts
				(xy -0.4572 -1.6256) (xy -0.7112 -2.1336) (xy -0.2032 -2.1336)
			)
			(stroke
				(width 0)
				(type default)
			)
			(fill yes)
			(layer "F.Fab")
		)
		(pad "1" smd rect
			(at -0.424942 -0.849884)
			(size 0.3556 0.9144)
			(layers "F.Cu" "F.Mask" "F.Paste")
			(net "USB3_01_MUX_FB_TXP")
		)
		(pad "2" smd rect
			(at -0.424942 0.849884)
			(size 0.3556 0.9144)
			(layers "F.Cu" "F.Mask" "F.Paste")
			(net "USB3_01_FB_TXP")
		)
		(pad "3" smd rect
			(at 0.424942 0.849884)
			(size 0.3556 0.9144)
			(layers "F.Cu" "F.Mask" "F.Paste")
			(net "USB3_01_FB_TXN")
		)
		(pad "4" smd rect
			(at 0.424942 -0.849884)
			(size 0.3556 0.9144)
			(layers "F.Cu" "F.Mask" "F.Paste")
			(net "USB3_01_MUX_FB_TXN")
		)
	)
	(footprint ""
		(layer "F.Cu")
		(at 84.201 -94.488)
		(property "Reference" "R97"
			(at 0 0 0)
			(layer "F.SilkS")
			(hide yes)
			(effects
				(font
					(size 1.27 1.27)
				)
			)
		)
		(property "Value" ""
			(at 0 0 0)
			(layer "F.Fab")
			(effects
				(font
					(size 1.27 1.27)
				)
			)
		)
		(duplicate_pad_numbers_are_jumpers no)
		(fp_line
			(start -0.7874 -0.4064)
			(end 0.7874 -0.4064)
			(stroke
				(width 0.1524)
				(type default)
			)
			(layer "F.SilkS")
		)
		(fp_line
			(start -0.7874 0.4064)
			(end -0.7874 -0.4064)
			(stroke
				(width 0.1524)
				(type default)
			)
			(layer "F.SilkS")
		)
		(fp_line
			(start 0.7874 -0.4064)
			(end 0.7874 0.4064)
			(stroke
				(width 0.1524)
				(type default)
			)
			(layer "F.SilkS")
		)
		(fp_line
			(start 0.7874 0.4064)
			(end -0.7874 0.4064)
			(stroke
				(width 0.1524)
				(type default)
			)
			(layer "F.SilkS")
		)
		(fp_line
			(start -0.67945 -0.305054)
			(end -0.12065 -0.305054)
			(stroke
				(width 0.1)
				(type default)
			)
			(layer "F.Fab")
		)
		(fp_line
			(start -0.67945 0.3048)
			(end -0.67945 -0.305054)
			(stroke
				(width 0.1)
				(type default)
			)
			(layer "F.Fab")
		)
		(fp_line
			(start -0.12065 -0.305054)
			(end -0.12065 -0.2794)
			(stroke
				(width 0.1)
				(type default)
			)
			(layer "F.Fab")
		)
		(fp_line
			(start -0.12065 -0.2794)
			(end 0.12065 -0.2794)
			(stroke
				(width 0.1)
				(type default)
			)
			(layer "F.Fab")
		)
		(fp_line
			(start -0.12065 0.2794)
			(end -0.12065 0.3048)
			(stroke
				(width 0.1)
				(type default)
			)
			(layer "F.Fab")
		)
		(fp_line
			(start -0.12065 0.3048)
			(end -0.67945 0.3048)
			(stroke
				(width 0.1)
				(type default)
			)
			(layer "F.Fab")
		)
		(fp_line
			(start 0.120396 0.2794)
			(end -0.12065 0.2794)
			(stroke
				(width 0.1)
				(type default)
			)
			(layer "F.Fab")
		)
		(fp_line
			(start 0.120396 0.3048)
			(end 0.120396 0.2794)
			(stroke
				(width 0.1)
				(type default)
			)
			(layer "F.Fab")
		)
		(fp_line
			(start 0.12065 -0.3048)
			(end 0.67945 -0.3048)
			(stroke
				(width 0.1)
				(type default)
			)
			(layer "F.Fab")
		)
		(fp_line
			(start 0.12065 -0.2794)
			(end 0.12065 -0.3048)
			(stroke
				(width 0.1)
				(type default)
			)
			(layer "F.Fab")
		)
		(fp_line
			(start 0.67945 -0.3048)
			(end 0.67945 0.3048)
			(stroke
				(width 0.1)
				(type default)
			)
			(layer "F.Fab")
		)
		(fp_line
			(start 0.67945 0.3048)
			(end 0.120396 0.3048)
			(stroke
				(width 0.1)
				(type default)
			)
			(layer "F.Fab")
		)
		(pad "1" smd circle
			(at -0.40005 0)
			(size 0 0)
			(layers "F.Cu" "F.Mask" "F.Paste")
			(net "SPI_BMC_TPM_MOSI_R")
		)
		(pad "2" smd circle
			(at 0.40005 0)
			(size 0 0)
			(layers "F.Cu" "F.Mask" "F.Paste")
			(net "SPI_BMC_TPM_MOSI")
		)
	)
	(footprint ""
		(layer "F.Cu")
		(at 10.98296 -78.236318 90)
		(property "Reference" "PC229"
			(at 0 0 90)
			(layer "F.SilkS")
			(hide yes)
			(effects
				(font
					(size 1.27 1.27)
				)
			)
		)
		(property "Value" ""
			(at 0 0 90)
			(layer "F.Fab")
			(effects
				(font
					(size 1.27 1.27)
				)
			)
		)
		(duplicate_pad_numbers_are_jumpers no)
		(fp_line
			(start 1.651 -0.8382)
			(end 1.651 0.8382)
			(stroke
				(width 0.1524)
				(type default)
			)
			(layer "F.SilkS")
		)
		(fp_line
			(start -1.651 -0.8382)
			(end 1.651 -0.8382)
			(stroke
				(width 0.1524)
				(type default)
			)
			(layer "F.SilkS")
		)
		(fp_line
			(start 1.651 0.8382)
			(end -1.651 0.8382)
			(stroke
				(width 0.1524)
				(type default)
			)
			(layer "F.SilkS")
		)
		(fp_line
			(start 0 0.8382)
			(end 0 -0.8382)
			(stroke
				(width 0.1524)
				(type default)
			)
			(layer "F.SilkS")
		)
		(fp_line
			(start -1.651 0.8382)
			(end -1.651 -0.8382)
			(stroke
				(width 0.1524)
				(type default)
			)
			(layer "F.SilkS")
		)
		(fp_line
			(start 1.55956 -0.7366)
			(end 1.524 -0.7366)
			(stroke
				(width 0.1)
				(type default)
			)
			(layer "F.Fab")
		)
		(fp_line
			(start 1.524 -0.7366)
			(end -1.524 -0.7366)
			(stroke
				(width 0.1)
				(type default)
			)
			(layer "F.Fab")
		)
		(fp_line
			(start -1.524 -0.7366)
			(end -1.55956 -0.7366)
			(stroke
				(width 0.1)
				(type default)
			)
			(layer "F.Fab")
		)
		(fp_line
			(start -1.55956 -0.7366)
			(end -1.55956 0.7366)
			(stroke
				(width 0.1)
				(type default)
			)
			(layer "F.Fab")
		)
		(fp_line
			(start 1.55956 0.7366)
			(end 1.55956 -0.7366)
			(stroke
				(width 0.1)
				(type default)
			)
			(layer "F.Fab")
		)
		(fp_line
			(start 1.524 0.7366)
			(end 1.55956 0.7366)
			(stroke
				(width 0.1)
				(type default)
			)
			(layer "F.Fab")
		)
		(fp_line
			(start -1.524 0.7366)
			(end 1.524 0.7366)
			(stroke
				(width 0.1)
				(type default)
			)
			(layer "F.Fab")
		)
		(fp_line
			(start -1.55956 0.7366)
			(end -1.524 0.7366)
			(stroke
				(width 0.1)
				(type default)
			)
			(layer "F.Fab")
		)
		(pad "1" smd rect
			(at -0.94996 0 270)
			(size 1.1176 1.3716)
			(layers "F.Cu" "F.Mask" "F.Paste")
			(net "P3V3_AUX")
		)
		(pad "2" smd rect
			(at 0.94996 0 270)
			(size 1.1176 1.3716)
			(layers "F.Cu" "F.Mask" "F.Paste")
			(net "GND")
		)
	)
)
